(kicad_pcb
	(version 20260206)
	(generator "pcbnew")
	(generator_version "10.0")
	(general
		(thickness 1.6)
		(legacy_teardrops no)
	)
	(paper "A4")
	(title_block
		(title "timecard-production-celestica-r4006 — R4006-B0001-02_R01.brd")
		(comment 1 "Time Appliance Project (Time Card) / footprints 187-190 of 1113")
	)
	(layers
		(0 "F.Cu" signal "TOP")
		(4 "In1.Cu" signal "L02_GND1")
		(6 "In2.Cu" signal "L03_SIG1")
		(8 "In3.Cu" signal "L04_GND2")
		(10 "In4.Cu" signal "L05_VCC1")
		(12 "In5.Cu" signal "L06_VCC2")
		(14 "In6.Cu" signal "L07_GND3")
		(16 "In7.Cu" signal "L08_SIG2")
		(18 "In8.Cu" signal "L09_GND4")
		(2 "B.Cu" signal "BOTTOM")
		(9 "F.Adhes" user "F.Adhesive")
		(11 "B.Adhes" user "B.Adhesive")
		(13 "F.Paste" user "Package Geometry/Pastemask Top")
		(15 "B.Paste" user "Package Geometry/Pastemask Bottom")
		(5 "F.SilkS" user "Ref Des/Silkscreen Top")
		(7 "B.SilkS" user "Ref Des/Silkscreen Bottom")
		(1 "F.Mask" user "Board Geometry/Soldermask Top")
		(3 "B.Mask" user "Board Geometry/Soldermask Bottom")
		(17 "Dwgs.User" user "User.Drawings")
		(19 "Cmts.User" user "User.Comments")
		(21 "Eco1.User" user "User.Eco1")
		(23 "Eco2.User" user "User.Eco2")
		(25 "Edge.Cuts" user "Board Geometry/Outline")
		(27 "Margin" user)
		(31 "F.CrtYd" user "Package Geometry/Place Bound Top")
		(29 "B.CrtYd" user "Package Geometry/Place Bound Bottom")
		(35 "F.Fab" user "Ref Des/Assembly Top")
		(33 "B.Fab" user "Ref Des/Assembly Bottom")
	)
	(footprint ""
		(layer "F.Cu")
		(at 142.4432 -71.6534 90)
		(property "Reference" "J14"
			(at 7.17423 0.4318 0)
			(unlocked yes)
			(layer "F.SilkS")
			(effects
				(font
					(size 0.7874 0.5842)
					(thickness 0.1524)
				)
			)
		)
		(property "Value" ""
			(at 0 0 90)
			(layer "F.Fab")
			(effects
				(font
					(size 1.27 1.27)
				)
			)
		)
		(property "User Part Number" "PARTNUM*"
			(at 0.191262 6.403086 90)
			(unlocked yes)
			(layer "Cmts.User")
			(hide yes)
			(effects
				(font
					(size 0.7874 0.5842)
					(thickness 0.1524)
				)
			)
		)
		(property "Device Type" "G200_10283_01-G200-10283-01"
			(at 0.241808 5.437378 90)
			(unlocked yes)
			(layer "F.Fab")
			(hide yes)
			(effects
				(font
					(size 0.7874 0.5842)
					(thickness 0.1524)
				)
			)
		)
		(duplicate_pad_numbers_are_jumpers no)
		(fp_line
			(start 6.4008 -4.6355)
			(end 6.4008 4.6355)
			(stroke
				(width 0.1)
				(type default)
			)
			(layer "F.SilkS")
		)
		(fp_line
			(start -6.4008 -4.6355)
			(end 6.4008 -4.6355)
			(stroke
				(width 0.1)
				(type default)
			)
			(layer "F.SilkS")
		)
		(fp_line
			(start 6.4008 4.6355)
			(end -6.4008 4.6355)
			(stroke
				(width 0.1)
				(type default)
			)
			(layer "F.SilkS")
		)
		(fp_line
			(start -6.4008 4.6355)
			(end -6.4008 -4.6355)
			(stroke
				(width 0.1)
				(type default)
			)
			(layer "F.SilkS")
		)
		(fp_rect
			(start 6.6548 -4.8895)
			(end -6.6548 4.8895)
			(stroke
				(width 0)
				(type default)
			)
			(fill no)
			(layer "F.CrtYd")
		)
		(fp_line
			(start 5.386832 -3.7084)
			(end 5.386832 -2.436876)
			(stroke
				(width 0.1)
				(type default)
			)
			(layer "F.Fab")
		)
		(fp_line
			(start 4.746752 -3.7084)
			(end 5.386832 -3.7084)
			(stroke
				(width 0.1)
				(type default)
			)
			(layer "F.Fab")
		)
		(fp_line
			(start 2.872232 -3.7084)
			(end 2.872232 -2.436876)
			(stroke
				(width 0.1)
				(type default)
			)
			(layer "F.Fab")
		)
		(fp_line
			(start 2.232152 -3.7084)
			(end 2.872232 -3.7084)
			(stroke
				(width 0.1)
				(type default)
			)
			(layer "F.Fab")
		)
		(fp_line
			(start 0.306832 -3.7084)
			(end 0.306832 -2.436876)
			(stroke
				(width 0.1)
				(type default)
			)
			(layer "F.Fab")
		)
		(fp_line
			(start -0.333248 -3.7084)
			(end 0.306832 -3.7084)
			(stroke
				(width 0.1)
				(type default)
			)
			(layer "F.Fab")
		)
		(fp_line
			(start -2.233168 -3.7084)
			(end -2.233168 -2.436876)
			(stroke
				(width 0.1)
				(type default)
			)
			(layer "F.Fab")
		)
		(fp_line
			(start -2.873248 -3.7084)
			(end -2.233168 -3.7084)
			(stroke
				(width 0.1)
				(type default)
			)
			(layer "F.Fab")
		)
		(fp_line
			(start -4.773168 -3.7084)
			(end -4.773168 -2.436876)
			(stroke
				(width 0.1)
				(type default)
			)
			(layer "F.Fab")
		)
		(fp_line
			(start -5.413248 -3.7084)
			(end -4.773168 -3.7084)
			(stroke
				(width 0.1)
				(type default)
			)
			(layer "F.Fab")
		)
		(fp_line
			(start 6.145022 -2.4384)
			(end 6.145022 2.4384)
			(stroke
				(width 0.1)
				(type default)
			)
			(layer "F.Fab")
		)
		(fp_line
			(start -6.145022 -2.4384)
			(end 6.145022 -2.4384)
			(stroke
				(width 0.1)
				(type default)
			)
			(layer "F.Fab")
		)
		(fp_line
			(start 5.386832 -2.436876)
			(end 4.746752 -2.436876)
			(stroke
				(width 0.1)
				(type default)
			)
			(layer "F.Fab")
		)
		(fp_line
			(start 4.746752 -2.436876)
			(end 4.746752 -3.7084)
			(stroke
				(width 0.1)
				(type default)
			)
			(layer "F.Fab")
		)
		(fp_line
			(start 2.872232 -2.436876)
			(end 2.232152 -2.436876)
			(stroke
				(width 0.1)
				(type default)
			)
			(layer "F.Fab")
		)
		(fp_line
			(start 2.232152 -2.436876)
			(end 2.232152 -3.7084)
			(stroke
				(width 0.1)
				(type default)
			)
			(layer "F.Fab")
		)
		(fp_line
			(start 0.306832 -2.436876)
			(end -0.333248 -2.436876)
			(stroke
				(width 0.1)
				(type default)
			)
			(layer "F.Fab")
		)
		(fp_line
			(start -0.333248 -2.436876)
			(end -0.333248 -3.7084)
			(stroke
				(width 0.1)
				(type default)
			)
			(layer "F.Fab")
		)
		(fp_line
			(start -2.233168 -2.436876)
			(end -2.873248 -2.436876)
			(stroke
				(width 0.1)
				(type default)
			)
			(layer "F.Fab")
		)
		(fp_line
			(start -2.873248 -2.436876)
			(end -2.873248 -3.7084)
			(stroke
				(width 0.1)
				(type default)
			)
			(layer "F.Fab")
		)
		(fp_line
			(start -4.773168 -2.436876)
			(end -5.413248 -2.436876)
			(stroke
				(width 0.1)
				(type default)
			)
			(layer "F.Fab")
		)
		(fp_line
			(start -5.413248 -2.436876)
			(end -5.413248 -3.7084)
			(stroke
				(width 0.1)
				(type default)
			)
			(layer "F.Fab")
		)
		(fp_line
			(start 6.145022 2.4384)
			(end -6.145022 2.4384)
			(stroke
				(width 0.1)
				(type default)
			)
			(layer "F.Fab")
		)
		(fp_line
			(start 5.386832 2.4384)
			(end 5.386832 3.709924)
			(stroke
				(width 0.1)
				(type default)
			)
			(layer "F.Fab")
		)
		(fp_line
			(start 4.746752 2.4384)
			(end 5.386832 2.4384)
			(stroke
				(width 0.1)
				(type default)
			)
			(layer "F.Fab")
		)
		(fp_line
			(start 2.846832 2.4384)
			(end 2.846832 3.709924)
			(stroke
				(width 0.1)
				(type default)
			)
			(layer "F.Fab")
		)
		(fp_line
			(start 2.206752 2.4384)
			(end 2.846832 2.4384)
			(stroke
				(width 0.1)
				(type default)
			)
			(layer "F.Fab")
		)
		(fp_line
			(start 0.306832 2.4384)
			(end 0.306832 3.709924)
			(stroke
				(width 0.1)
				(type default)
			)
			(layer "F.Fab")
		)
		(fp_line
			(start -0.333248 2.4384)
			(end 0.306832 2.4384)
			(stroke
				(width 0.1)
				(type default)
			)
			(layer "F.Fab")
		)
		(fp_line
			(start -2.233168 2.4384)
			(end -2.233168 3.709924)
			(stroke
				(width 0.1)
				(type default)
			)
			(layer "F.Fab")
		)
		(fp_line
			(start -2.873248 2.4384)
			(end -2.233168 2.4384)
			(stroke
				(width 0.1)
				(type default)
			)
			(layer "F.Fab")
		)
		(fp_line
			(start -4.747768 2.4384)
			(end -4.747768 3.709924)
			(stroke
				(width 0.1)
				(type default)
			)
			(layer "F.Fab")
		)
		(fp_line
			(start -5.387848 2.4384)
			(end -4.747768 2.4384)
			(stroke
				(width 0.1)
				(type default)
			)
			(layer "F.Fab")
		)
		(fp_line
			(start -6.145022 2.4384)
			(end -6.145022 -2.4384)
			(stroke
				(width 0.1)
				(type default)
			)
			(layer "F.Fab")
		)
		(fp_line
			(start 5.386832 3.709924)
			(end 4.746752 3.709924)
			(stroke
				(width 0.1)
				(type default)
			)
			(layer "F.Fab")
		)
		(fp_line
			(start 4.746752 3.709924)
			(end 4.746752 2.4384)
			(stroke
				(width 0.1)
				(type default)
			)
			(layer "F.Fab")
		)
		(fp_line
			(start 2.846832 3.709924)
			(end 2.206752 3.709924)
			(stroke
				(width 0.1)
				(type default)
			)
			(layer "F.Fab")
		)
		(fp_line
			(start 2.206752 3.709924)
			(end 2.206752 2.4384)
			(stroke
				(width 0.1)
				(type default)
			)
			(layer "F.Fab")
		)
		(fp_line
			(start 0.306832 3.709924)
			(end -0.333248 3.709924)
			(stroke
				(width 0.1)
				(type default)
			)
			(layer "F.Fab")
		)
		(fp_line
			(start -0.333248 3.709924)
			(end -0.333248 2.4384)
			(stroke
				(width 0.1)
				(type default)
			)
			(layer "F.Fab")
		)
		(fp_line
			(start -2.233168 3.709924)
			(end -2.873248 3.709924)
			(stroke
				(width 0.1)
				(type default)
			)
			(layer "F.Fab")
		)
		(fp_line
			(start -2.873248 3.709924)
			(end -2.873248 2.4384)
			(stroke
				(width 0.1)
				(type default)
			)
			(layer "F.Fab")
		)
		(fp_line
			(start -4.747768 3.709924)
			(end -5.387848 3.709924)
			(stroke
				(width 0.1)
				(type default)
			)
			(layer "F.Fab")
		)
		(fp_line
			(start -5.387848 3.709924)
			(end -5.387848 2.4384)
			(stroke
				(width 0.1)
				(type default)
			)
			(layer "F.Fab")
		)
		(fp_text user "10"
			(at 6.28523 -5.4102 0)
			(unlocked yes)
			(layer "F.SilkS")
			(effects
				(font
					(size 0.7874 0.5842)
					(thickness 0.1524)
				)
			)
		)
		(fp_text user "2"
			(at -6.92277 -4.5212 0)
			(unlocked yes)
			(layer "F.SilkS")
			(effects
				(font
					(size 0.7874 0.5842)
					(thickness 0.1524)
				)
			)
		)
		(fp_text user "9"
			(at 5.90423 5.5118 0)
			(unlocked yes)
			(layer "F.SilkS")
			(effects
				(font
					(size 0.7874 0.5842)
					(thickness 0.1524)
				)
			)
		)
		(fp_text user "1"
			(at -5.14477 5.7658 0)
			(unlocked yes)
			(layer "F.SilkS")
			(effects
				(font
					(size 0.7874 0.5842)
					(thickness 0.1524)
				)
			)
		)
		(fp_text user "10"
			(at 5.15493 -4.9022 0)
			(unlocked yes)
			(layer "F.Fab")
			(effects
				(font
					(size 0.7874 0.5842)
					(thickness 0.1524)
				)
			)
		)
		(fp_text user "2"
			(at -5.65277 -4.9022 0)
			(unlocked yes)
			(layer "F.Fab")
			(effects
				(font
					(size 0.7874 0.5842)
					(thickness 0.1524)
				)
			)
		)
		(fp_text user "9"
			(at 5.02793 4.2418 0)
			(unlocked yes)
			(layer "F.Fab")
			(effects
				(font
					(size 0.7874 0.5842)
					(thickness 0.1524)
				)
			)
		)
		(fp_text user "1"
			(at -5.13207 4.4958 0)
			(unlocked yes)
			(layer "F.Fab")
			(effects
				(font
					(size 0.7874 0.5842)
					(thickness 0.1524)
				)
			)
		)
		(pad "1" smd rect
			(at -5.08 2.605024 90)
			(size 1.27 3.556)
			(layers "F.Cu" "F.Mask" "F.Paste")
			(net "FT4232_FPGA_TCK")
		)
		(pad "2" smd rect
			(at -5.08 -2.605024 90)
			(size 1.27 3.556)
			(layers "F.Cu" "F.Mask" "F.Paste")
			(net "SG")
		)
		(pad "3" smd rect
			(at -2.54 2.605024 90)
			(size 1.27 3.556)
			(layers "F.Cu" "F.Mask" "F.Paste")
			(net "FT4232_FPGA_TDO")
		)
		(pad "4" smd rect
			(at -2.54 -2.605024 90)
			(size 1.27 3.556)
			(layers "F.Cu" "F.Mask" "F.Paste")
			(net "UNNAMED_127_G2001028301_I427_4")
		)
		(pad "5" smd rect
			(at 0 2.605024 90)
			(size 1.27 3.556)
			(layers "F.Cu" "F.Mask" "F.Paste")
			(net "FT4232_FPGA_TMS")
		)
		(pad "6" smd rect
			(at 0 -2.605024 90)
			(size 1.27 3.556)
			(layers "F.Cu" "F.Mask" "F.Paste")
			(net "Net_625")
		)
		(pad "7" smd rect
			(at 2.54 2.605024 90)
			(size 1.27 3.556)
			(layers "F.Cu" "F.Mask" "F.Paste")
			(net "Net_626")
		)
		(pad "8" smd rect
			(at 2.54 -2.605024 90)
			(size 1.27 3.556)
			(layers "F.Cu" "F.Mask" "F.Paste")
			(net "Net_627")
		)
		(pad "9" smd rect
			(at 5.08 2.605024 90)
			(size 1.27 3.556)
			(layers "F.Cu" "F.Mask" "F.Paste")
			(net "FT4232_FPGA_TDI")
		)
		(pad "10" smd rect
			(at 5.08 -2.605024 90)
			(size 1.27 3.556)
			(layers "F.Cu" "F.Mask" "F.Paste")
			(net "SG")
		)
		(zone
			(layer "F.Cu")
			(hatch none 0.5)
			(connect_pads
				(clearance 0)
			)
			(min_thickness 0.25)
			(keepout
				(tracks allowed)
				(vias not_allowed)
				(pads allowed)
				(copperpour not_allowed)
				(footprints allowed)
			)
			(placement
				(enabled no)
				(sheetname "")
			)
			(fill
				(thermal_gap 0.5)
				(thermal_bridge_width 0.5)
				(island_removal_mode 0)
			)
			(polygon
				(pts
					(xy 141.6304 -77.371702) (xy 141.6304 -65.941702) (xy 143.256 -65.941702) (xy 143.256 -77.371702)
				)
			)
		)
	)
	(footprint ""
		(layer "F.Cu")
		(at 80.772 -56.1086 180)
		(property "Reference" "R289"
			(at 10.287 19.51863 0)
			(unlocked yes)
			(layer "F.SilkS")
			(effects
				(font
					(size 0.7874 0.5842)
					(thickness 0.1524)
				)
			)
		)
		(property "Value" "VAL*"
			(at 0.02032 2.13233 180)
			(unlocked yes)
			(layer "F.Fab")
			(hide yes)
			(effects
				(font
					(size 0.7874 0.5842)
					(thickness 0.1524)
				)
			)
		)
		(property "Tolerance" "TOL*"
			(at 0.044704 3.05435 180)
			(unlocked yes)
			(layer "Cmts.User")
			(hide yes)
			(effects
				(font
					(size 0.7874 0.5842)
					(thickness 0.1524)
				)
			)
		)
		(property "User Part Number" "PARTNUM*"
			(at 0.02032 4.024884 180)
			(unlocked yes)
			(layer "Cmts.User")
			(hide yes)
			(effects
				(font
					(size 0.7874 0.5842)
					(thickness 0.1524)
				)
			)
		)
		(property "Device Type" "RESISTOR-G155-14701-01,4.7KOHMA"
			(at 0.008382 1.210564 180)
			(unlocked yes)
			(layer "F.Fab")
			(hide yes)
			(effects
				(font
					(size 0.7874 0.5842)
					(thickness 0.1524)
				)
			)
		)
		(duplicate_pad_numbers_are_jumpers no)
		(fp_line
			(start 1.143 0.5588)
			(end 1.143 -0.5588)
			(stroke
				(width 0.1)
				(type default)
			)
			(layer "F.SilkS")
		)
		(fp_line
			(start 1.143 -0.5588)
			(end -1.143 -0.5588)
			(stroke
				(width 0.1)
				(type default)
			)
			(layer "F.SilkS")
		)
		(fp_line
			(start -1.143 0.5588)
			(end 1.143 0.5588)
			(stroke
				(width 0.1)
				(type default)
			)
			(layer "F.SilkS")
		)
		(fp_line
			(start -1.143 -0.5588)
			(end -1.143 0.5588)
			(stroke
				(width 0.1)
				(type default)
			)
			(layer "F.SilkS")
		)
		(fp_rect
			(start 1.143 -0.5588)
			(end -1.143 0.5588)
			(stroke
				(width 0)
				(type default)
			)
			(fill no)
			(layer "F.CrtYd")
		)
		(fp_line
			(start 0.508 0.3048)
			(end 0.508 -0.3048)
			(stroke
				(width 0.1)
				(type default)
			)
			(layer "F.Fab")
		)
		(fp_line
			(start 0.508 -0.3048)
			(end -0.508 -0.3048)
			(stroke
				(width 0.1)
				(type default)
			)
			(layer "F.Fab")
		)
		(fp_line
			(start -0.508 0.3048)
			(end 0.508 0.3048)
			(stroke
				(width 0.1)
				(type default)
			)
			(layer "F.Fab")
		)
		(fp_line
			(start -0.508 -0.3048)
			(end -0.508 0.3048)
			(stroke
				(width 0.1)
				(type default)
			)
			(layer "F.Fab")
		)
		(pad "1" smd rect
			(at -0.5334 0 180)
			(size 0.7112 0.6096)
			(layers "F.Cu" "F.Mask" "F.Paste")
			(net "XP3R3V_FPGA")
		)
		(pad "2" smd rect
			(at 0.5334 0 180)
			(size 0.7112 0.6096)
			(layers "F.Cu" "F.Mask" "F.Paste")
			(net "FPGA_IN_BNO080_INT_N")
		)
		(zone
			(layer "F.Cu")
			(hatch none 0.5)
			(connect_pads
				(clearance 0)
			)
			(min_thickness 0.25)
			(keepout
				(tracks allowed)
				(vias not_allowed)
				(pads allowed)
				(copperpour not_allowed)
				(footprints allowed)
			)
			(placement
				(enabled no)
				(sheetname "")
			)
			(fill
				(thermal_gap 0.5)
				(thermal_bridge_width 0.5)
				(island_removal_mode 0)
			)
			(polygon
				(pts
					(xy 80.6958 -55.8038) (xy 80.8482 -55.8038) (xy 80.8482 -56.4134) (xy 80.6958 -56.4134)
				)
			)
		)
	)
	(footprint ""
		(layer "F.Cu")
		(at 47.879 -75.184 90)
		(property "Reference" "C302"
			(at -0.381 2.19837 90)
			(unlocked yes)
			(layer "F.SilkS")
			(effects
				(font
					(size 0.7874 0.5842)
					(thickness 0.1524)
				)
			)
		)
		(property "Value" "VAL*"
			(at 0.0762 2.067306 90)
			(unlocked yes)
			(layer "F.Fab")
			(hide yes)
			(effects
				(font
					(size 0.7874 0.5842)
					(thickness 0.1524)
				)
			)
		)
		(property "Tolerance" "TOL*"
			(at 0.0762 3.032506 90)
			(unlocked yes)
			(layer "Cmts.User")
			(hide yes)
			(effects
				(font
					(size 0.7874 0.5842)
					(thickness 0.1524)
				)
			)
		)
		(property "User Part Number" "PARTNUM*"
			(at 0.1016 4.023106 90)
			(unlocked yes)
			(layer "Cmts.User")
			(hide yes)
			(effects
				(font
					(size 0.7874 0.5842)
					(thickness 0.1524)
				)
			)
		)
		(property "Device Type" "CAPACITOR-G105-0B104-EK,0.1UF,A"
			(at 0.0508 1.127506 90)
			(unlocked yes)
			(layer "F.Fab")
			(hide yes)
			(effects
				(font
					(size 0.7874 0.5842)
					(thickness 0.1524)
				)
			)
		)
		(duplicate_pad_numbers_are_jumpers no)
		(fp_line
			(start 1.143 -0.5588)
			(end -1.143 -0.5588)
			(stroke
				(width 0.1)
				(type default)
			)
			(layer "F.SilkS")
		)
		(fp_line
			(start -1.143 -0.5588)
			(end -1.143 0.5588)
			(stroke
				(width 0.1)
				(type default)
			)
			(layer "F.SilkS")
		)
		(fp_line
			(start 1.143 0.5588)
			(end 1.143 -0.5588)
			(stroke
				(width 0.1)
				(type default)
			)
			(layer "F.SilkS")
		)
		(fp_line
			(start -1.143 0.5588)
			(end 1.143 0.5588)
			(stroke
				(width 0.1)
				(type default)
			)
			(layer "F.SilkS")
		)
		(fp_poly
			(pts
				(xy -1.143 0.5588) (xy 1.143 0.5588) (xy 1.143 -0.5588) (xy -1.143 -0.5588)
			)
			(stroke
				(width 0)
				(type default)
			)
			(fill no)
			(layer "F.CrtYd")
		)
		(fp_line
			(start 0.508 -0.3048)
			(end -0.508 -0.3048)
			(stroke
				(width 0.1)
				(type default)
			)
			(layer "F.Fab")
		)
		(fp_line
			(start -0.508 -0.3048)
			(end -0.508 0.3048)
			(stroke
				(width 0.1)
				(type default)
			)
			(layer "F.Fab")
		)
		(fp_line
			(start 0.508 0.3048)
			(end 0.508 -0.3048)
			(stroke
				(width 0.1)
				(type default)
			)
			(layer "F.Fab")
		)
		(fp_line
			(start -0.508 0.3048)
			(end 0.508 0.3048)
			(stroke
				(width 0.1)
				(type default)
			)
			(layer "F.Fab")
		)
		(pad "1" smd rect
			(at -0.5334 0 90)
			(size 0.7112 0.6096)
			(layers "F.Cu" "F.Mask" "F.Paste")
			(net "UNNAMED_525_CAPACITOR_I14_1")
		)
		(pad "2" smd rect
			(at 0.5334 0 90)
			(size 0.7112 0.6096)
			(layers "F.Cu" "F.Mask" "F.Paste")
			(net "SG")
		)
		(zone
			(layer "F.Cu")
			(hatch none 0.5)
			(connect_pads
				(clearance 0)
			)
			(min_thickness 0.25)
			(keepout
				(tracks not_allowed)
				(vias allowed)
				(pads allowed)
				(copperpour not_allowed)
				(footprints allowed)
			)
			(placement
				(enabled no)
				(sheetname "")
			)
			(fill
				(thermal_gap 0.5)
				(thermal_bridge_width 0.5)
				(island_removal_mode 0)
			)
			(polygon
				(pts
					(xy 48.1838 -75.1078) (xy 48.1838 -75.2602) (xy 47.5742 -75.2602) (xy 47.5742 -75.1078)
				)
			)
		)
		(zone
			(layer "F.Cu")
			(hatch none 0.5)
			(connect_pads
				(clearance 0)
			)
			(min_thickness 0.25)
			(keepout
				(tracks allowed)
				(vias not_allowed)
				(pads allowed)
				(copperpour not_allowed)
				(footprints allowed)
			)
			(placement
				(enabled no)
				(sheetname "")
			)
			(fill
				(thermal_gap 0.5)
				(thermal_bridge_width 0.5)
				(island_removal_mode 0)
			)
			(polygon
				(pts
					(xy 48.1838 -75.1078) (xy 48.1838 -75.2602) (xy 47.5742 -75.2602) (xy 47.5742 -75.1078)
				)
			)
		)
	)
	(footprint ""
		(layer "F.Cu")
		(at 52.451 -122.428)
		(property "Reference" "SP78"
			(at 0 0 0)
			(layer "F.SilkS")
			(hide yes)
			(effects
				(font
					(size 1.27 1.27)
				)
			)
		)
		(property "Value" ""
			(at 0 0 0)
			(layer "F.Fab")
			(effects
				(font
					(size 1.27 1.27)
				)
			)
		)
		(duplicate_pad_numbers_are_jumpers no)
	)
)
